(kicad_pcb
	(version 20260206)
	(generator "pcbnew")
	(generator_version "10.0")
	(general
		(thickness 1.6)
		(legacy_teardrops no)
	)
	(paper "A4")
	(title_block
		(title "v1-chassis-manager — T6M_CM_d_v01_1031_1645.brd")
		(comment 1 "Open CloudServer (Microsoft) / footprints 685-693 of 2512")
	)
	(layers
		(0 "F.Cu" signal "TOP")
		(4 "In1.Cu" signal "GND1")
		(6 "In2.Cu" signal "IN1")
		(8 "In3.Cu" signal "VCC1")
		(10 "In4.Cu" signal "VCC2")
		(12 "In5.Cu" signal "GND2")
		(14 "In6.Cu" signal "IN2")
		(16 "In7.Cu" signal "IN3")
		(18 "In8.Cu" signal "GND3")
		(2 "B.Cu" signal "BOTTOM")
		(9 "F.Adhes" user "F.Adhesive")
		(11 "B.Adhes" user "B.Adhesive")
		(13 "F.Paste" user "Package Geometry/Pastemask Top")
		(15 "B.Paste" user "Package Geometry/Pastemask Bottom")
		(5 "F.SilkS" user "Ref Des/Silkscreen Top")
		(7 "B.SilkS" user "Ref Des/Silkscreen Bottom")
		(1 "F.Mask" user "Board Geometry/Soldermask Top")
		(3 "B.Mask" user "Board Geometry/Soldermask Bottom")
		(17 "Dwgs.User" user "User.Drawings")
		(19 "Cmts.User" user "User.Comments")
		(21 "Eco1.User" user "User.Eco1")
		(23 "Eco2.User" user "User.Eco2")
		(25 "Edge.Cuts" user "Board Geometry/Outline")
		(27 "Margin" user)
		(31 "F.CrtYd" user "Package Geometry/Place Bound Top")
		(29 "B.CrtYd" user "Package Geometry/Place Bound Bottom")
		(35 "F.Fab" user "Ref Des/Assembly Top")
		(33 "B.Fab" user "Ref Des/Assembly Bottom")
	)
	(footprint ""
		(layer "F.Cu")
		(at 166.715694 -121.57202 180)
		(property "Reference" "R1045"
			(at 2.798064 -9.851644 0)
			(unlocked yes)
			(layer "F.SilkS")
			(effects
				(font
					(size 0.7874 0.5842)
					(thickness 0.1524)
				)
				(justify left)
			)
		)
		(property "Value" ""
			(at 0 0 180)
			(layer "F.Fab")
			(effects
				(font
					(size 1.27 1.27)
				)
			)
		)
		(duplicate_pad_numbers_are_jumpers no)
		(fp_line
			(start 0.7874 0.4064)
			(end -0.7874 0.4064)
			(stroke
				(width 0.1524)
				(type default)
			)
			(layer "F.SilkS")
		)
		(fp_line
			(start 0.7874 -0.4064)
			(end 0.7874 0.4064)
			(stroke
				(width 0.1524)
				(type default)
			)
			(layer "F.SilkS")
		)
		(fp_line
			(start -0.7874 0.4064)
			(end -0.7874 -0.4064)
			(stroke
				(width 0.1524)
				(type default)
			)
			(layer "F.SilkS")
		)
		(fp_line
			(start -0.7874 -0.4064)
			(end 0.7874 -0.4064)
			(stroke
				(width 0.1524)
				(type default)
			)
			(layer "F.SilkS")
		)
		(fp_poly
			(pts
				(xy -0.508 0.2794) (xy -0.508 0.2286) (xy -0.635 0.2286) (xy -0.635 -0.254) (xy -0.5334 -0.254)
				(xy -0.5334 -0.2794) (xy 0.5334 -0.2794) (xy 0.5334 -0.254) (xy 0.635 -0.254) (xy 0.635 0.254) (xy 0.5334 0.254)
				(xy 0.5334 0.2794)
			)
			(stroke
				(width 0)
				(type default)
			)
			(fill no)
			(layer "F.CrtYd")
		)
		(pad "1" smd rect
			(at 0.40005 0 180)
			(size 0.4572 0.508)
			(layers "F.Cu" "F.Mask" "F.Paste")
			(net "FM_NODE1_DDR3_SYSPWRGD_R_L")
		)
		(pad "2" smd rect
			(at -0.40005 0 180)
			(size 0.4572 0.508)
			(layers "F.Cu" "F.Mask" "F.Paste")
			(net "FM_NODE1_DDR3_SYSPWRGD_L")
		)
	)
	(footprint ""
		(layer "F.Cu")
		(at 191.389 -120.65 180)
		(property "Reference" "R1266"
			(at -0.2032 -2.64287 0)
			(unlocked yes)
			(layer "F.SilkS")
			(effects
				(font
					(size 0.7874 0.5842)
					(thickness 0.1524)
				)
				(justify left)
			)
		)
		(property "Value" ""
			(at 0 0 180)
			(layer "F.Fab")
			(effects
				(font
					(size 1.27 1.27)
				)
			)
		)
		(duplicate_pad_numbers_are_jumpers no)
		(fp_line
			(start 0.7874 0.4064)
			(end -0.7874 0.4064)
			(stroke
				(width 0.1524)
				(type default)
			)
			(layer "F.SilkS")
		)
		(fp_line
			(start 0.7874 -0.4064)
			(end 0.7874 0.4064)
			(stroke
				(width 0.1524)
				(type default)
			)
			(layer "F.SilkS")
		)
		(fp_line
			(start -0.7874 0.4064)
			(end -0.7874 -0.4064)
			(stroke
				(width 0.1524)
				(type default)
			)
			(layer "F.SilkS")
		)
		(fp_line
			(start -0.7874 -0.4064)
			(end 0.7874 -0.4064)
			(stroke
				(width 0.1524)
				(type default)
			)
			(layer "F.SilkS")
		)
		(fp_poly
			(pts
				(xy -0.508 0.2794) (xy -0.508 0.2286) (xy -0.635 0.2286) (xy -0.635 -0.254) (xy -0.5334 -0.254)
				(xy -0.5334 -0.2794) (xy 0.5334 -0.2794) (xy 0.5334 -0.254) (xy 0.635 -0.254) (xy 0.635 0.254) (xy 0.5334 0.254)
				(xy 0.5334 0.2794)
			)
			(stroke
				(width 0)
				(type default)
			)
			(fill no)
			(layer "F.CrtYd")
		)
		(pad "1" smd rect
			(at 0.40005 0 180)
			(size 0.4572 0.508)
			(layers "F.Cu" "F.Mask" "F.Paste")
			(net "SIO_JTAG_CPLD1_TDI")
		)
		(pad "2" smd rect
			(at -0.40005 0 180)
			(size 0.4572 0.508)
			(layers "F.Cu" "F.Mask" "F.Paste")
			(net "GND")
		)
	)
	(footprint ""
		(layer "F.Cu")
		(at 100.471732 -166.113206 -90)
		(property "Reference" "U70"
			(at 68.287392 -87.225124 0)
			(unlocked yes)
			(layer "F.SilkS")
			(effects
				(font
					(size 0.7874 0.5842)
					(thickness 0.1524)
				)
			)
		)
		(property "Value" ""
			(at 0 0 270)
			(layer "F.Fab")
			(effects
				(font
					(size 1.27 1.27)
				)
			)
		)
		(duplicate_pad_numbers_are_jumpers no)
		(fp_line
			(start -2.4892 1.524)
			(end -2.4892 0.5588)
			(stroke
				(width 0.1524)
				(type default)
			)
			(layer "F.SilkS")
		)
		(fp_line
			(start 2.4892 1.524)
			(end -2.4892 1.524)
			(stroke
				(width 0.1524)
				(type default)
			)
			(layer "F.SilkS")
		)
		(fp_line
			(start -2.4892 0.5588)
			(end -1.9304 0)
			(stroke
				(width 0.1524)
				(type default)
			)
			(layer "F.SilkS")
		)
		(fp_line
			(start -1.9304 0)
			(end -2.4892 -0.5588)
			(stroke
				(width 0.1524)
				(type default)
			)
			(layer "F.SilkS")
		)
		(fp_line
			(start -2.4892 -0.5588)
			(end -2.4892 -1.524)
			(stroke
				(width 0.1524)
				(type default)
			)
			(layer "F.SilkS")
		)
		(fp_line
			(start -2.4892 -1.524)
			(end 2.4892 -1.524)
			(stroke
				(width 0.1524)
				(type default)
			)
			(layer "F.SilkS")
		)
		(fp_line
			(start 2.4892 -1.524)
			(end 2.4892 1.524)
			(stroke
				(width 0.1524)
				(type default)
			)
			(layer "F.SilkS")
		)
		(fp_circle
			(center -1.905 1.016)
			(end -1.905 0.762)
			(stroke
				(width 0.1524)
				(type default)
			)
			(fill no)
			(layer "F.SilkS")
		)
		(fp_poly
			(pts
				(xy -2.4003 3.5179) (xy -2.4003 2.0066) (xy -2.4892 2.0066) (xy -2.4892 -2.0066) (xy -2.4003 -2.0066)
				(xy -2.4003 -3.5179) (xy 2.4003 -3.5179) (xy 2.4003 -2.0066) (xy 2.4892 -2.0066) (xy 2.4892 2.0066)
				(xy 2.4003 2.0066) (xy 2.4003 3.5179)
			)
			(stroke
				(width 0)
				(type default)
			)
			(fill no)
			(layer "F.CrtYd")
		)
		(pad "1" smd rect
			(at -2.2225 2.7432 270)
			(size 0.3556 1.5494)
			(layers "F.Cu" "F.Mask" "F.Paste")
			(net "I2C_SCL_FANCTRL2_R")
		)
		(pad "2" smd rect
			(at -1.5875 2.7432 270)
			(size 0.3556 1.5494)
			(layers "F.Cu" "F.Mask" "F.Paste")
			(net "GND")
		)
		(pad "3" smd rect
			(at -0.9525 2.7432 270)
			(size 0.3556 1.5494)
			(layers "F.Cu" "F.Mask" "F.Paste")
			(net "P3V3_NODE1")
		)
		(pad "4" smd rect
			(at -0.3175 2.7432 270)
			(size 0.3556 1.5494)
			(layers "F.Cu" "F.Mask" "F.Paste")
			(net "PU_FAN_TACH")
		)
		(pad "5" smd rect
			(at 0.3175 2.7432 270)
			(size 0.3556 1.5494)
			(layers "F.Cu" "F.Mask" "F.Paste")
			(net "Net_2252")
		)
		(pad "6" smd rect
			(at 0.9525 2.7432 270)
			(size 0.3556 1.5494)
			(layers "F.Cu" "F.Mask" "F.Paste")
			(net "FAN5_TACH_IN")
		)
		(pad "7" smd rect
			(at 1.5875 2.7432 270)
			(size 0.3556 1.5494)
			(layers "F.Cu" "F.Mask" "F.Paste")
			(net "FAN6_TACH_IN")
		)
		(pad "8" smd rect
			(at 2.2225 2.7432 270)
			(size 0.3556 1.5494)
			(layers "F.Cu" "F.Mask" "F.Paste")
			(net "Net_2251")
		)
		(pad "9" smd rect
			(at 2.2225 -2.7432 270)
			(size 0.3556 1.5494)
			(layers "F.Cu" "F.Mask" "F.Paste")
			(net "PU_FAN_TACH")
		)
		(pad "10" smd rect
			(at 1.5875 -2.7432 270)
			(size 0.3556 1.5494)
			(layers "F.Cu" "F.Mask" "F.Paste")
			(net "Net_2250")
		)
		(pad "11" smd rect
			(at 0.9525 -2.7432 270)
			(size 0.3556 1.5494)
			(layers "F.Cu" "F.Mask" "F.Paste")
			(net "FNACTRL2_ADD")
		)
		(pad "12" smd rect
			(at 0.3175 -2.7432 270)
			(size 0.3556 1.5494)
			(layers "F.Cu" "F.Mask" "F.Paste")
			(net "FNACTRL2_TMP_IN")
		)
		(pad "13" smd rect
			(at -0.3175 -2.7432 270)
			(size 0.3556 1.5494)
			(layers "F.Cu" "F.Mask" "F.Paste")
			(net "FNACTRL2_T_ST")
		)
		(pad "14" smd rect
			(at -0.9525 -2.7432 270)
			(size 0.3556 1.5494)
			(layers "F.Cu" "F.Mask" "F.Paste")
			(net "I2C_ALERT_FNACTRL2_N")
		)
		(pad "15" smd rect
			(at -1.5875 -2.7432 270)
			(size 0.3556 1.5494)
			(layers "F.Cu" "F.Mask" "F.Paste")
			(net "Net_2253")
		)
		(pad "16" smd rect
			(at -2.2225 -2.7432 270)
			(size 0.3556 1.5494)
			(layers "F.Cu" "F.Mask" "F.Paste")
			(net "I2C_SDA_FANCTRL2_R")
		)
	)
	(footprint ""
		(layer "F.Cu")
		(at 152.67051 -147.041362)
		(property "Reference" "C528"
			(at -1.316482 -3.967226 0)
			(unlocked yes)
			(layer "F.SilkS")
			(effects
				(font
					(size 0.635 0.4064)
					(thickness 0.1524)
				)
				(justify left)
			)
		)
		(property "Value" ""
			(at 0 0 0)
			(layer "F.Fab")
			(effects
				(font
					(size 1.27 1.27)
				)
			)
		)
		(duplicate_pad_numbers_are_jumpers no)
		(fp_line
			(start -0.7874 -0.4064)
			(end 0.7874 -0.4064)
			(stroke
				(width 0.1524)
				(type default)
			)
			(layer "F.SilkS")
		)
		(fp_line
			(start -0.7874 0.4064)
			(end -0.7874 -0.4064)
			(stroke
				(width 0.1524)
				(type default)
			)
			(layer "F.SilkS")
		)
		(fp_line
			(start 0 0.381)
			(end 0 -0.381)
			(stroke
				(width 0.1524)
				(type default)
			)
			(layer "F.SilkS")
		)
		(fp_line
			(start 0.7874 -0.4064)
			(end 0.7874 0.4064)
			(stroke
				(width 0.1524)
				(type default)
			)
			(layer "F.SilkS")
		)
		(fp_line
			(start 0.7874 0.4064)
			(end -0.7874 0.4064)
			(stroke
				(width 0.1524)
				(type default)
			)
			(layer "F.SilkS")
		)
		(fp_poly
			(pts
				(xy -0.5334 0.254) (xy -0.635 0.254) (xy -0.635 0.2286) (xy -0.635 -0.254) (xy -0.5334 -0.254) (xy -0.5334 -0.2794)
				(xy 0.5334 -0.2794) (xy 0.5334 -0.254) (xy 0.635 -0.254) (xy 0.635 0.254) (xy 0.5334 0.254) (xy 0.5334 0.2794)
				(xy -0.508 0.2794) (xy -0.5334 0.2794)
			)
			(stroke
				(width 0)
				(type default)
			)
			(fill no)
			(layer "F.CrtYd")
		)
		(pad "1" smd rect
			(at 0.40005 0)
			(size 0.4572 0.508)
			(layers "F.Cu" "F.Mask" "F.Paste")
			(net "LAN2_LED_LINK_100_N")
		)
		(pad "2" smd rect
			(at -0.40005 0)
			(size 0.4572 0.508)
			(layers "F.Cu" "F.Mask" "F.Paste")
			(net "GND")
		)
	)
	(footprint ""
		(layer "F.Cu")
		(at 187.7695 -163.024566)
		(property "Reference" "R1277"
			(at -1.685544 5.368544 0)
			(unlocked yes)
			(layer "F.SilkS")
			(effects
				(font
					(size 0.7874 0.5842)
					(thickness 0.1524)
				)
				(justify left)
			)
		)
		(property "Value" ""
			(at 0 0 0)
			(layer "F.Fab")
			(effects
				(font
					(size 1.27 1.27)
				)
			)
		)
		(duplicate_pad_numbers_are_jumpers no)
		(fp_line
			(start -0.7874 -0.4064)
			(end 0.7874 -0.4064)
			(stroke
				(width 0.1524)
				(type default)
			)
			(layer "F.SilkS")
		)
		(fp_line
			(start -0.7874 0.4064)
			(end -0.7874 -0.4064)
			(stroke
				(width 0.1524)
				(type default)
			)
			(layer "F.SilkS")
		)
		(fp_line
			(start 0.7874 -0.4064)
			(end 0.7874 0.4064)
			(stroke
				(width 0.1524)
				(type default)
			)
			(layer "F.SilkS")
		)
		(fp_line
			(start 0.7874 0.4064)
			(end -0.7874 0.4064)
			(stroke
				(width 0.1524)
				(type default)
			)
			(layer "F.SilkS")
		)
		(fp_poly
			(pts
				(xy -0.508 0.2794) (xy -0.508 0.2286) (xy -0.635 0.2286) (xy -0.635 -0.254) (xy -0.5334 -0.254)
				(xy -0.5334 -0.2794) (xy 0.5334 -0.2794) (xy 0.5334 -0.254) (xy 0.635 -0.254) (xy 0.635 0.254) (xy 0.5334 0.254)
				(xy 0.5334 0.2794)
			)
			(stroke
				(width 0)
				(type default)
			)
			(fill no)
			(layer "F.CrtYd")
		)
		(pad "1" smd rect
			(at 0.40005 0)
			(size 0.4572 0.508)
			(layers "F.Cu" "F.Mask" "F.Paste")
			(net "N54134271")
		)
		(pad "2" smd rect
			(at -0.40005 0)
			(size 0.4572 0.508)
			(layers "F.Cu" "F.Mask" "F.Paste")
			(net "LAN2_P1_R")
		)
	)
	(footprint ""
		(layer "F.Cu")
		(at 131.230878 -51.45151 -90)
		(property "Reference" "R1164"
			(at -16.31569 -30.669992 90)
			(unlocked yes)
			(layer "F.SilkS")
			(effects
				(font
					(size 0.7874 0.5842)
					(thickness 0.1524)
				)
				(justify left)
			)
		)
		(property "Value" ""
			(at 0 0 270)
			(layer "F.Fab")
			(effects
				(font
					(size 1.27 1.27)
				)
			)
		)
		(duplicate_pad_numbers_are_jumpers no)
		(fp_line
			(start -0.7874 0.4064)
			(end -0.7874 -0.4064)
			(stroke
				(width 0.1524)
				(type default)
			)
			(layer "F.SilkS")
		)
		(fp_line
			(start 0.7874 0.4064)
			(end -0.7874 0.4064)
			(stroke
				(width 0.1524)
				(type default)
			)
			(layer "F.SilkS")
		)
		(fp_line
			(start -0.7874 -0.4064)
			(end 0.7874 -0.4064)
			(stroke
				(width 0.1524)
				(type default)
			)
			(layer "F.SilkS")
		)
		(fp_line
			(start 0.7874 -0.4064)
			(end 0.7874 0.4064)
			(stroke
				(width 0.1524)
				(type default)
			)
			(layer "F.SilkS")
		)
		(fp_poly
			(pts
				(xy -0.508 0.2794) (xy -0.508 0.2286) (xy -0.635 0.2286) (xy -0.635 -0.254) (xy -0.5334 -0.254)
				(xy -0.5334 -0.2794) (xy 0.5334 -0.2794) (xy 0.5334 -0.254) (xy 0.635 -0.254) (xy 0.635 0.254) (xy 0.5334 0.254)
				(xy 0.5334 0.2794)
			)
			(stroke
				(width 0)
				(type default)
			)
			(fill no)
			(layer "F.CrtYd")
		)
		(pad "1" smd rect
			(at 0.40005 0 270)
			(size 0.4572 0.508)
			(layers "F.Cu" "F.Mask" "F.Paste")
			(net "UART_RTS_P4_R_N")
		)
		(pad "2" smd rect
			(at -0.40005 0 270)
			(size 0.4572 0.508)
			(layers "F.Cu" "F.Mask" "F.Paste")
			(net "UART_RTS_P4_N")
		)
	)
	(footprint ""
		(layer "F.Cu")
		(at 18.746724 -146.512534)
		(property "Reference" "C413"
			(at -5.747004 0.141986 0)
			(unlocked yes)
			(layer "F.SilkS")
			(effects
				(font
					(size 0.7874 0.5842)
					(thickness 0.1524)
				)
				(justify left)
			)
		)
		(property "Value" ""
			(at 0 0 0)
			(layer "F.Fab")
			(effects
				(font
					(size 1.27 1.27)
				)
			)
		)
		(duplicate_pad_numbers_are_jumpers no)
		(fp_line
			(start -1.905 -0.8636)
			(end 1.905 -0.8636)
			(stroke
				(width 0.1524)
				(type default)
			)
			(layer "F.SilkS")
		)
		(fp_line
			(start -1.905 0.8636)
			(end -1.905 -0.8636)
			(stroke
				(width 0.1524)
				(type default)
			)
			(layer "F.SilkS")
		)
		(fp_line
			(start 0 0.8382)
			(end 0 -0.8382)
			(stroke
				(width 0.1524)
				(type default)
			)
			(layer "F.SilkS")
		)
		(fp_line
			(start 1.905 -0.8636)
			(end 1.905 0.8636)
			(stroke
				(width 0.1524)
				(type default)
			)
			(layer "F.SilkS")
		)
		(fp_line
			(start 1.905 0.8636)
			(end -1.905 0.8636)
			(stroke
				(width 0.1524)
				(type default)
			)
			(layer "F.SilkS")
		)
		(fp_rect
			(start -1.524 0.7366)
			(end 1.524 -0.7366)
			(stroke
				(width 0)
				(type default)
			)
			(fill no)
			(layer "F.CrtYd")
		)
		(pad "1" smd rect
			(at 0.94996 0)
			(size 1.1176 1.3716)
			(layers "F.Cu" "F.Mask" "F.Paste")
			(net "P3V3_NODE1")
		)
		(pad "2" smd rect
			(at -0.94996 0)
			(size 1.1176 1.3716)
			(layers "F.Cu" "F.Mask" "F.Paste")
			(net "GND")
		)
	)
	(footprint ""
		(layer "F.Cu")
		(at 34.318956 -19.453352)
		(property "Reference" "R217"
			(at -3.041396 1.304798 0)
			(unlocked yes)
			(layer "F.SilkS")
			(effects
				(font
					(size 0.7874 0.5842)
					(thickness 0.1524)
				)
				(justify left)
			)
		)
		(property "Value" ""
			(at 0 0 0)
			(layer "F.Fab")
			(effects
				(font
					(size 1.27 1.27)
				)
			)
		)
		(duplicate_pad_numbers_are_jumpers no)
		(fp_line
			(start -0.7874 -0.4064)
			(end 0.7874 -0.4064)
			(stroke
				(width 0.1524)
				(type default)
			)
			(layer "F.SilkS")
		)
		(fp_line
			(start -0.7874 0.4064)
			(end -0.7874 -0.4064)
			(stroke
				(width 0.1524)
				(type default)
			)
			(layer "F.SilkS")
		)
		(fp_line
			(start 0.7874 -0.4064)
			(end 0.7874 0.4064)
			(stroke
				(width 0.1524)
				(type default)
			)
			(layer "F.SilkS")
		)
		(fp_line
			(start 0.7874 0.4064)
			(end -0.7874 0.4064)
			(stroke
				(width 0.1524)
				(type default)
			)
			(layer "F.SilkS")
		)
		(fp_poly
			(pts
				(xy -0.508 0.2794) (xy -0.508 0.2286) (xy -0.635 0.2286) (xy -0.635 -0.254) (xy -0.5334 -0.254)
				(xy -0.5334 -0.2794) (xy 0.5334 -0.2794) (xy 0.5334 -0.254) (xy 0.635 -0.254) (xy 0.635 0.254) (xy 0.5334 0.254)
				(xy 0.5334 0.2794)
			)
			(stroke
				(width 0)
				(type default)
			)
			(fill no)
			(layer "F.CrtYd")
		)
		(pad "1" smd rect
			(at 0.40005 0)
			(size 0.4572 0.508)
			(layers "F.Cu" "F.Mask" "F.Paste")
			(net "P1V5_NODE1_DDR3_VREF0_D")
		)
		(pad "2" smd rect
			(at -0.40005 0)
			(size 0.4572 0.508)
			(layers "F.Cu" "F.Mask" "F.Paste")
			(net "PV_VDDR_NODE1_VREF_LM321")
		)
	)
	(footprint ""
		(layer "F.Cu")
		(at 14.359382 -157.329378 180)
		(property "Reference" "R1274"
			(at 1.619504 -2.323846 0)
			(unlocked yes)
			(layer "F.SilkS")
			(effects
				(font
					(size 0.7874 0.5842)
					(thickness 0.1524)
				)
				(justify left)
			)
		)
		(property "Value" ""
			(at 0 0 180)
			(layer "F.Fab")
			(effects
				(font
					(size 1.27 1.27)
				)
			)
		)
		(duplicate_pad_numbers_are_jumpers no)
		(fp_line
			(start 0.7874 0.4064)
			(end -0.7874 0.4064)
			(stroke
				(width 0.1524)
				(type default)
			)
			(layer "F.SilkS")
		)
		(fp_line
			(start 0.7874 -0.4064)
			(end 0.7874 0.4064)
			(stroke
				(width 0.1524)
				(type default)
			)
			(layer "F.SilkS")
		)
		(fp_line
			(start -0.7874 0.4064)
			(end -0.7874 -0.4064)
			(stroke
				(width 0.1524)
				(type default)
			)
			(layer "F.SilkS")
		)
		(fp_line
			(start -0.7874 -0.4064)
			(end 0.7874 -0.4064)
			(stroke
				(width 0.1524)
				(type default)
			)
			(layer "F.SilkS")
		)
		(fp_poly
			(pts
				(xy -0.508 0.2794) (xy -0.508 0.2286) (xy -0.635 0.2286) (xy -0.635 -0.254) (xy -0.5334 -0.254)
				(xy -0.5334 -0.2794) (xy 0.5334 -0.2794) (xy 0.5334 -0.254) (xy 0.635 -0.254) (xy 0.635 0.254) (xy 0.5334 0.254)
				(xy 0.5334 0.2794)
			)
			(stroke
				(width 0)
				(type default)
			)
			(fill no)
			(layer "F.CrtYd")
		)
		(pad "1" smd rect
			(at 0.40005 0 180)
			(size 0.4572 0.508)
			(layers "F.Cu" "F.Mask" "F.Paste")
			(net "N54065132")
		)
		(pad "2" smd rect
			(at -0.40005 0 180)
			(size 0.4572 0.508)
			(layers "F.Cu" "F.Mask" "F.Paste")
			(net "LAN1_P2_R")
		)
	)
)
